# T6G (Grand Teton) — schematic netlist excerpt (pin names and nets, part order shuffled) for the footprints in the layout excerpt that follows; sources: Cadence DE-HDL packaged netlist, KiCad conversion of 04192023_DAF0TMB3IC0_F0TG_MB_C_brd_V02_OCP.brd

R420  Q_RES  1K 1% EMPTY  pkg 0402LF  page 28 : A = PVDD11_S3_P0 ; B = I3C_1_SPD_DDRGL_CPU0_R_SDA
C6044  Q_CAP  0.1UF 25V 10% X7R  pkg 0402  page 177 : A = P3V3_AUX_CPU0_USB_AVDD33 ; B = GND

(kicad_pcb
	(version 20260206)
	(generator "pcbnew")
	(generator_version "10.0")
	(general
		(thickness 1.6)
		(legacy_teardrops no)
	)
	(paper "A4")
	(title_block
		(title "04192023_DAF0TMB3IC0_F0TG_MB_C_brd_V02_OCP.brd")
		(comment 1 "Grand Teton / footprints 5468-5470 of 8354")
	)
	(layers
		(0 "F.Cu" signal "TOP")
		(4 "In1.Cu" signal "GND")
		(6 "In2.Cu" signal "IN1")
		(8 "In3.Cu" signal "GND1")
		(10 "In4.Cu" signal "IN2")
		(12 "In5.Cu" signal "GND2")
		(14 "In6.Cu" signal "IN3")
		(16 "In7.Cu" signal "GND3")
		(18 "In8.Cu" signal "VCC")
		(20 "In9.Cu" signal "VCC1")
		(22 "In10.Cu" signal "GND4")
		(24 "In11.Cu" signal "IN4")
		(26 "In12.Cu" signal "GND5")
		(28 "In13.Cu" signal "IN5")
		(30 "In14.Cu" signal "GND6")
		(32 "In15.Cu" signal "IN6")
		(34 "In16.Cu" signal "GND7")
		(2 "B.Cu" signal "BOTTOM")
		(9 "F.Adhes" user "F.Adhesive")
		(11 "B.Adhes" user "B.Adhesive")
		(13 "F.Paste" user "Package Geometry/Pastemask Top")
		(15 "B.Paste" user "Package Geometry/Pastemask Bottom")
		(5 "F.SilkS" user "Ref Des/Silkscreen Top")
		(7 "B.SilkS" user "Ref Des/Silkscreen Bottom")
		(1 "F.Mask" user "Board Geometry/Soldermask Top")
		(3 "B.Mask" user "Board Geometry/Soldermask Bottom")
		(17 "Dwgs.User" user "User.Drawings")
		(19 "Cmts.User" user "User.Comments")
		(21 "Eco1.User" user "User.Eco1")
		(23 "Eco2.User" user "User.Eco2")
		(25 "Edge.Cuts" user "Board Geometry/Outline")
		(27 "Margin" user)
		(31 "F.CrtYd" user "Package Geometry/Place Bound Top")
		(29 "B.CrtYd" user "Package Geometry/Place Bound Bottom")
		(35 "F.Fab" user "Ref Des/Assembly Top")
		(33 "B.Fab" user "Ref Des/Assembly Bottom")
	)
	(footprint ""
		(layer "B.Cu")
		(at 95.064072 -477.345502)
		(property "Reference" "ME7"
			(at 0 0 0)
			(layer "B.SilkS")
			(hide yes)
			(effects
				(font
					(size 1.27 1.27)
				)
				(justify mirror)
			)
		)
		(property "Value" ""
			(at 0 0 0)
			(layer "B.Fab")
			(effects
				(font
					(size 1.27 1.27)
				)
				(justify mirror)
			)
		)
		(duplicate_pad_numbers_are_jumpers no)
		(zone
			(layer "B.Cu")
			(hatch none 0.5)
			(connect_pads
				(clearance 0)
			)
			(min_thickness 0.25)
			(keepout
				(tracks allowed)
				(vias allowed)
				(pads allowed)
				(copperpour allowed)
				(footprints not_allowed)
			)
			(placement
				(enabled no)
				(sheetname "")
			)
			(fill
				(thermal_gap 0.5)
				(thermal_bridge_width 0.5)
				(island_removal_mode 0)
			)
			(polygon
				(pts
					(arc
						(start 453.286368 -125.607064)
						(mid 433.286408 -125.607064)
						(end 453.286368 -125.607064)
					)
				)
			)
		)
	)
	(footprint ""
		(layer "B.Cu")
		(at 382.016 -205.101952 -90)
		(property "Reference" "R420"
			(at 0 0 90)
			(layer "B.SilkS")
			(hide yes)
			(effects
				(font
					(size 1.27 1.27)
				)
				(justify mirror)
			)
		)
		(property "Value" ""
			(at 0 0 90)
			(layer "B.Fab")
			(effects
				(font
					(size 1.27 1.27)
				)
				(justify mirror)
			)
		)
		(duplicate_pad_numbers_are_jumpers no)
		(fp_line
			(start -0.7874 0.4064)
			(end 0.7874 0.4064)
			(stroke
				(width 0.1524)
				(type default)
			)
			(layer "B.SilkS")
		)
		(fp_line
			(start 0.7874 0.4064)
			(end 0.7874 -0.4064)
			(stroke
				(width 0.1524)
				(type default)
			)
			(layer "B.SilkS")
		)
		(fp_line
			(start -0.7874 -0.4064)
			(end -0.7874 0.4064)
			(stroke
				(width 0.1524)
				(type default)
			)
			(layer "B.SilkS")
		)
		(fp_line
			(start 0.7874 -0.4064)
			(end -0.7874 -0.4064)
			(stroke
				(width 0.1524)
				(type default)
			)
			(layer "B.SilkS")
		)
		(fp_line
			(start -0.67945 0.3048)
			(end -0.120396 0.3048)
			(stroke
				(width 0.1)
				(type default)
			)
			(layer "B.Fab")
		)
		(fp_line
			(start -0.120396 0.3048)
			(end -0.120396 0.2794)
			(stroke
				(width 0.1)
				(type default)
			)
			(layer "B.Fab")
		)
		(fp_line
			(start 0.12065 0.3048)
			(end 0.67945 0.3048)
			(stroke
				(width 0.1)
				(type default)
			)
			(layer "B.Fab")
		)
		(fp_line
			(start 0.67945 0.3048)
			(end 0.67945 -0.305054)
			(stroke
				(width 0.1)
				(type default)
			)
			(layer "B.Fab")
		)
		(fp_line
			(start -0.120396 0.2794)
			(end 0.12065 0.2794)
			(stroke
				(width 0.1)
				(type default)
			)
			(layer "B.Fab")
		)
		(fp_line
			(start 0.12065 0.2794)
			(end 0.12065 0.3048)
			(stroke
				(width 0.1)
				(type default)
			)
			(layer "B.Fab")
		)
		(fp_line
			(start -0.12065 -0.2794)
			(end -0.12065 -0.3048)
			(stroke
				(width 0.1)
				(type default)
			)
			(layer "B.Fab")
		)
		(fp_line
			(start 0.12065 -0.2794)
			(end -0.12065 -0.2794)
			(stroke
				(width 0.1)
				(type default)
			)
			(layer "B.Fab")
		)
		(fp_line
			(start -0.67945 -0.3048)
			(end -0.67945 0.3048)
			(stroke
				(width 0.1)
				(type default)
			)
			(layer "B.Fab")
		)
		(fp_line
			(start -0.12065 -0.3048)
			(end -0.67945 -0.3048)
			(stroke
				(width 0.1)
				(type default)
			)
			(layer "B.Fab")
		)
		(fp_line
			(start 0.12065 -0.305054)
			(end 0.12065 -0.2794)
			(stroke
				(width 0.1)
				(type default)
			)
			(layer "B.Fab")
		)
		(fp_line
			(start 0.67945 -0.305054)
			(end 0.12065 -0.305054)
			(stroke
				(width 0.1)
				(type default)
			)
			(layer "B.Fab")
		)
		(pad "1" smd circle
			(at 0.40005 0 90)
			(size 0 0)
			(layers "B.Cu" "B.Mask" "B.Paste")
			(net "PVDD11_S3_P0")
		)
		(pad "2" smd circle
			(at -0.40005 0 90)
			(size 0 0)
			(layers "B.Cu" "B.Mask" "B.Paste")
			(net "I3C_1_SPD_DDRGL_CPU0_R_SDA")
		)
	)
	(footprint ""
		(layer "B.Cu")
		(at 138.34872 -35.304222 -90)
		(property "Reference" "C6044"
			(at 0 0 90)
			(layer "B.SilkS")
			(hide yes)
			(effects
				(font
					(size 1.27 1.27)
				)
				(justify mirror)
			)
		)
		(property "Value" ""
			(at 0 0 90)
			(layer "B.Fab")
			(effects
				(font
					(size 1.27 1.27)
				)
				(justify mirror)
			)
		)
		(duplicate_pad_numbers_are_jumpers no)
		(fp_line
			(start -0.7874 0.4064)
			(end 0.7874 0.4064)
			(stroke
				(width 0.1524)
				(type default)
			)
			(layer "B.SilkS")
		)
		(fp_line
			(start 0.7874 0.4064)
			(end 0.7874 -0.4064)
			(stroke
				(width 0.1524)
				(type default)
			)
			(layer "B.SilkS")
		)
		(fp_line
			(start -0.7874 -0.4064)
			(end -0.7874 0.4064)
			(stroke
				(width 0.1524)
				(type default)
			)
			(layer "B.SilkS")
		)
		(fp_line
			(start 0.7874 -0.4064)
			(end -0.7874 -0.4064)
			(stroke
				(width 0.1524)
				(type default)
			)
			(layer "B.SilkS")
		)
		(fp_line
			(start -0.67945 0.3048)
			(end -0.120396 0.3048)
			(stroke
				(width 0.1)
				(type default)
			)
			(layer "B.Fab")
		)
		(fp_line
			(start -0.120396 0.3048)
			(end -0.120396 0.2794)
			(stroke
				(width 0.1)
				(type default)
			)
			(layer "B.Fab")
		)
		(fp_line
			(start 0.12065 0.3048)
			(end 0.67945 0.3048)
			(stroke
				(width 0.1)
				(type default)
			)
			(layer "B.Fab")
		)
		(fp_line
			(start 0.67945 0.3048)
			(end 0.67945 -0.305054)
			(stroke
				(width 0.1)
				(type default)
			)
			(layer "B.Fab")
		)
		(fp_line
			(start -0.120396 0.2794)
			(end 0.12065 0.2794)
			(stroke
				(width 0.1)
				(type default)
			)
			(layer "B.Fab")
		)
		(fp_line
			(start 0.12065 0.2794)
			(end 0.12065 0.3048)
			(stroke
				(width 0.1)
				(type default)
			)
			(layer "B.Fab")
		)
		(fp_line
			(start -0.12065 -0.2794)
			(end -0.12065 -0.3048)
			(stroke
				(width 0.1)
				(type default)
			)
			(layer "B.Fab")
		)
		(fp_line
			(start 0.12065 -0.2794)
			(end -0.12065 -0.2794)
			(stroke
				(width 0.1)
				(type default)
			)
			(layer "B.Fab")
		)
		(fp_line
			(start -0.67945 -0.3048)
			(end -0.67945 0.3048)
			(stroke
				(width 0.1)
				(type default)
			)
			(layer "B.Fab")
		)
		(fp_line
			(start -0.12065 -0.3048)
			(end -0.67945 -0.3048)
			(stroke
				(width 0.1)
				(type default)
			)
			(layer "B.Fab")
		)
		(fp_line
			(start 0.12065 -0.305054)
			(end 0.12065 -0.2794)
			(stroke
				(width 0.1)
				(type default)
			)
			(layer "B.Fab")
		)
		(fp_line
			(start 0.67945 -0.305054)
			(end 0.12065 -0.305054)
			(stroke
				(width 0.1)
				(type default)
			)
			(layer "B.Fab")
		)
		(pad "1" smd circle
			(at 0.40005 0 90)
			(size 0 0)
			(layers "B.Cu" "B.Mask" "B.Paste")
			(net "P3V3_AUX_CPU0_USB_AVDD33")
		)
		(pad "2" smd circle
			(at -0.40005 0 90)
			(size 0 0)
			(layers "B.Cu" "B.Mask" "B.Paste")
			(net "GND")
		)
	)
)
